(kicad_pcb
	(version 20260206)
	(generator "pcbnew")
	(generator_version "10.0")
	(general
		(thickness 1.6)
		(legacy_teardrops no)
	)
	(paper "A4")
	(title_block
		(title "Wiwynn_Tioga_Pass_MB.brd")
		(comment 1 "Tioga Pass / footprints 1781-1788 of 4770")
	)
	(layers
		(0 "F.Cu" signal "TOP")
		(4 "In1.Cu" signal "L2GND")
		(6 "In2.Cu" signal "L3")
		(8 "In3.Cu" signal "L4GND")
		(10 "In4.Cu" signal "L5")
		(12 "In5.Cu" signal "L6GND")
		(14 "In6.Cu" signal "L7VCC")
		(16 "In7.Cu" signal "L8VCC")
		(18 "In8.Cu" signal "L9GND")
		(20 "In9.Cu" signal "L10")
		(22 "In10.Cu" signal "L11GND")
		(24 "In11.Cu" signal "L12")
		(26 "In12.Cu" signal "L13GND")
		(2 "B.Cu" signal "BOTTOM")
		(9 "F.Adhes" user "F.Adhesive")
		(11 "B.Adhes" user "B.Adhesive")
		(13 "F.Paste" user "Package Geometry/Pastemask Top")
		(15 "B.Paste" user "Package Geometry/Pastemask Bottom")
		(5 "F.SilkS" user "Ref Des/Silkscreen Top")
		(7 "B.SilkS" user "Ref Des/Silkscreen Bottom")
		(1 "F.Mask" user "Board Geometry/Soldermask Top")
		(3 "B.Mask" user "Board Geometry/Soldermask Bottom")
		(17 "Dwgs.User" user "User.Drawings")
		(19 "Cmts.User" user "User.Comments")
		(21 "Eco1.User" user "User.Eco1")
		(23 "Eco2.User" user "User.Eco2")
		(25 "Edge.Cuts" user "Board Geometry/Outline")
		(27 "Margin" user)
		(31 "F.CrtYd" user "Package Geometry/Place Bound Top")
		(29 "B.CrtYd" user "Package Geometry/Place Bound Bottom")
		(35 "F.Fab" user "Ref Des/Assembly Top")
		(33 "B.Fab" user "Ref Des/Assembly Bottom")
	)
	(footprint ""
		(layer "F.Cu")
		(at 399.372074 -84.309204 -90)
		(property "Reference" "Q8D2"
			(at 1.42748 3.45567 90)
			(unlocked yes)
			(layer "F.SilkS")
			(effects
				(font
					(size 0.7874 0.5842)
					(thickness 0.1524)
				)
				(justify left)
			)
		)
		(property "Value" ""
			(at 0 0 270)
			(layer "F.Fab")
			(effects
				(font
					(size 1.27 1.27)
				)
			)
		)
		(duplicate_pad_numbers_are_jumpers no)
		(fp_line
			(start 0.9525 2.4765)
			(end 1.778 2.4765)
			(stroke
				(width 0.1524)
				(type default)
			)
			(layer "F.SilkS")
		)
		(fp_line
			(start 1.778 2.4765)
			(end 1.778 1.5875)
			(stroke
				(width 0.1524)
				(type default)
			)
			(layer "F.SilkS")
		)
		(fp_line
			(start 0.381 0.635)
			(end 0.381 1.27)
			(stroke
				(width 0.1524)
				(type default)
			)
			(layer "F.SilkS")
		)
		(fp_line
			(start 0.9525 -0.5715)
			(end 1.778 -0.5715)
			(stroke
				(width 0.1524)
				(type default)
			)
			(layer "F.SilkS")
		)
		(fp_line
			(start 1.778 -0.5715)
			(end 1.778 0.3175)
			(stroke
				(width 0.1524)
				(type default)
			)
			(layer "F.SilkS")
		)
		(fp_circle
			(center -1.039368 -0.721614)
			(end -1.039368 -0.848614)
			(stroke
				(width 0.254)
				(type default)
			)
			(fill no)
			(layer "F.SilkS")
		)
		(fp_poly
			(pts
				(xy 1.778 2.4765) (xy 0.381 2.4765) (xy 0.381 -0.5715) (xy 1.778 -0.5715)
			)
			(stroke
				(width 0)
				(type default)
			)
			(fill no)
			(layer "F.CrtYd")
		)
		(fp_line
			(start 0.381 2.4765)
			(end 1.778 2.4765)
			(stroke
				(width 0.1)
				(type default)
			)
			(layer "F.Fab")
		)
		(fp_line
			(start 1.778 2.4765)
			(end 1.778 -0.5715)
			(stroke
				(width 0.1)
				(type default)
			)
			(layer "F.Fab")
		)
		(fp_line
			(start 0.381 -0.5715)
			(end 0.381 2.4765)
			(stroke
				(width 0.1)
				(type default)
			)
			(layer "F.Fab")
		)
		(fp_line
			(start 1.778 -0.5715)
			(end 0.381 -0.5715)
			(stroke
				(width 0.1)
				(type default)
			)
			(layer "F.Fab")
		)
		(fp_circle
			(center -0.9525 -0.9271)
			(end -0.9525 -1.0541)
			(stroke
				(width 0.254)
				(type default)
			)
			(fill no)
			(layer "F.Fab")
		)
		(pad "1" smd rect
			(at 0 0 270)
			(size 1.143 0.508)
			(layers "F.Cu" "F.Mask" "F.Paste")
			(net "RST_PLTRST_BUF_N")
		)
		(pad "2" smd rect
			(at 0 1.905 270)
			(size 1.143 0.508)
			(layers "F.Cu" "F.Mask" "F.Paste")
			(net "FM_PCH_BMC_THERMTRIP_EXI_STRAP_")
		)
		(pad "3" smd rect
			(at 2.159 0.9525 270)
			(size 1.143 0.508)
			(layers "F.Cu" "F.Mask" "F.Paste")
			(net "FM_PCH_BMC_THERMTRIP_N")
		)
	)
	(footprint ""
		(layer "F.Cu")
		(at 167.259 -71.5264)
		(property "Reference" "R4D42"
			(at 0 0 0)
			(layer "F.SilkS")
			(hide yes)
			(effects
				(font
					(size 1.27 1.27)
				)
			)
		)
		(property "Value" ""
			(at 0 0 0)
			(layer "F.Fab")
			(effects
				(font
					(size 1.27 1.27)
				)
			)
		)
		(duplicate_pad_numbers_are_jumpers no)
		(fp_poly
			(pts
				(xy -0.2794 -0.1016) (xy 0.2794 -0.1016) (xy 0.2794 0.9906) (xy -0.2794 0.9906)
			)
			(stroke
				(width 0)
				(type default)
			)
			(fill no)
			(layer "F.CrtYd")
		)
		(fp_line
			(start -0.2794 -0.1016)
			(end -0.2794 0.9906)
			(stroke
				(width 0.1)
				(type default)
			)
			(layer "F.Fab")
		)
		(fp_line
			(start -0.2794 0.9906)
			(end 0.2794 0.9906)
			(stroke
				(width 0.1)
				(type default)
			)
			(layer "F.Fab")
		)
		(fp_line
			(start 0.2794 -0.1016)
			(end -0.2794 -0.1016)
			(stroke
				(width 0.1)
				(type default)
			)
			(layer "F.Fab")
		)
		(fp_line
			(start 0.2794 0.9906)
			(end 0.2794 -0.1016)
			(stroke
				(width 0.1)
				(type default)
			)
			(layer "F.Fab")
		)
		(pad "1" smd rect
			(at 0 0)
			(size 0.508 0.508)
			(layers "F.Cu" "F.Mask" "F.Paste")
			(net "P3V3_STBY")
		)
		(pad "2" smd rect
			(at 0 0.889)
			(size 0.508 0.508)
			(layers "F.Cu" "F.Mask" "F.Paste")
			(net "PWRGD_PVCCIO_CPU1_R")
		)
		(zone
			(layer "F.Cu")
			(hatch none 0.5)
			(connect_pads
				(clearance 0)
			)
			(min_thickness 0.25)
			(keepout
				(tracks allowed)
				(vias not_allowed)
				(pads allowed)
				(copperpour not_allowed)
				(footprints allowed)
			)
			(placement
				(enabled no)
				(sheetname "")
			)
			(fill
				(thermal_gap 0.5)
				(thermal_bridge_width 0.5)
				(island_removal_mode 0)
			)
			(polygon
				(pts
					(xy 167.005 -71.2724) (xy 167.513 -71.2724) (xy 167.513 -70.8914) (xy 167.005 -70.8914)
				)
			)
		)
		(zone
			(layer "F.Cu")
			(hatch none 0.5)
			(connect_pads
				(clearance 0)
			)
			(min_thickness 0.25)
			(keepout
				(tracks not_allowed)
				(vias allowed)
				(pads allowed)
				(copperpour not_allowed)
				(footprints allowed)
			)
			(placement
				(enabled no)
				(sheetname "")
			)
			(fill
				(thermal_gap 0.5)
				(thermal_bridge_width 0.5)
				(island_removal_mode 0)
			)
			(polygon
				(pts
					(xy 167.005 -70.8914) (xy 167.513 -70.8914) (xy 167.513 -71.2724) (xy 167.005 -71.2724)
				)
			)
		)
	)
	(footprint ""
		(layer "F.Cu")
		(at 379.3109 -137.4648)
		(property "Reference" "C7A30"
			(at 0 0 0)
			(layer "F.SilkS")
			(hide yes)
			(effects
				(font
					(size 1.27 1.27)
				)
			)
		)
		(property "Value" ""
			(at 0 0 0)
			(layer "F.Fab")
			(effects
				(font
					(size 1.27 1.27)
				)
			)
		)
		(duplicate_pad_numbers_are_jumpers no)
		(fp_rect
			(start -0.7239 1.9939)
			(end 0.7239 -0.2159)
			(stroke
				(width 0)
				(type default)
			)
			(fill no)
			(layer "F.CrtYd")
		)
		(fp_line
			(start -0.7239 -0.2159)
			(end -0.7239 1.9939)
			(stroke
				(width 0.1)
				(type default)
			)
			(layer "F.Fab")
		)
		(fp_line
			(start -0.7239 1.9939)
			(end 0.7239 1.9939)
			(stroke
				(width 0.1)
				(type default)
			)
			(layer "F.Fab")
		)
		(fp_line
			(start 0.7239 -0.2159)
			(end -0.7239 -0.2159)
			(stroke
				(width 0.1)
				(type default)
			)
			(layer "F.Fab")
		)
		(fp_line
			(start 0.7239 1.9939)
			(end 0.7239 -0.2159)
			(stroke
				(width 0.1)
				(type default)
			)
			(layer "F.Fab")
		)
		(pad "1" smd rect
			(at 0 0)
			(size 1.27 1.016)
			(layers "F.Cu" "F.Mask" "F.Paste")
			(net "PVNN_PCH_STBY")
		)
		(pad "2" smd rect
			(at 0 1.778)
			(size 1.27 1.016)
			(layers "F.Cu" "F.Mask" "F.Paste")
			(net "GND")
		)
		(zone
			(layer "F.Cu")
			(hatch none 0.5)
			(connect_pads
				(clearance 0)
			)
			(min_thickness 0.25)
			(keepout
				(tracks not_allowed)
				(vias allowed)
				(pads allowed)
				(copperpour not_allowed)
				(footprints allowed)
			)
			(placement
				(enabled no)
				(sheetname "")
			)
			(fill
				(thermal_gap 0.5)
				(thermal_bridge_width 0.5)
				(island_removal_mode 0)
			)
			(polygon
				(pts
					(xy 378.6759 -136.1948) (xy 379.9459 -136.1948) (xy 379.9459 -136.9568) (xy 378.6759 -136.9568)
				)
			)
		)
	)
	(footprint ""
		(layer "F.Cu")
		(at 173.355 -131.5085)
		(property "Reference" "C4B6"
			(at 0 0 0)
			(layer "F.SilkS")
			(hide yes)
			(effects
				(font
					(size 1.27 1.27)
				)
			)
		)
		(property "Value" ""
			(at 0 0 0)
			(layer "F.Fab")
			(effects
				(font
					(size 1.27 1.27)
				)
			)
		)
		(duplicate_pad_numbers_are_jumpers no)
		(fp_poly
			(pts
				(xy 0.3048 -0.1016) (xy 0.3048 0.9906) (xy -0.3048 0.9906) (xy -0.3048 -0.1016)
			)
			(stroke
				(width 0)
				(type default)
			)
			(fill no)
			(layer "F.CrtYd")
		)
		(fp_line
			(start -0.3048 -0.1016)
			(end -0.3048 0.9906)
			(stroke
				(width 0.1)
				(type default)
			)
			(layer "F.Fab")
		)
		(fp_line
			(start -0.3048 0.9906)
			(end 0.3048 0.9906)
			(stroke
				(width 0.1)
				(type default)
			)
			(layer "F.Fab")
		)
		(fp_line
			(start 0.3048 -0.1016)
			(end -0.3048 -0.1016)
			(stroke
				(width 0.1)
				(type default)
			)
			(layer "F.Fab")
		)
		(fp_line
			(start 0.3048 0.9906)
			(end 0.3048 -0.1016)
			(stroke
				(width 0.1)
				(type default)
			)
			(layer "F.Fab")
		)
		(pad "1" smd rect
			(at 0 0)
			(size 0.508 0.508)
			(layers "F.Cu" "F.Mask" "F.Paste")
			(net "VR_PVPP_KLM_SS")
		)
		(pad "2" smd rect
			(at 0 0.889)
			(size 0.508 0.508)
			(layers "F.Cu" "F.Mask" "F.Paste")
			(net "AGND_PVPP_KLM")
		)
		(zone
			(layer "F.Cu")
			(hatch none 0.5)
			(connect_pads
				(clearance 0)
			)
			(min_thickness 0.25)
			(keepout
				(tracks allowed)
				(vias not_allowed)
				(pads allowed)
				(copperpour not_allowed)
				(footprints allowed)
			)
			(placement
				(enabled no)
				(sheetname "")
			)
			(fill
				(thermal_gap 0.5)
				(thermal_bridge_width 0.5)
				(island_removal_mode 0)
			)
			(polygon
				(pts
					(xy 173.101 -131.2545) (xy 173.609 -131.2545) (xy 173.609 -130.8735) (xy 173.101 -130.8735)
				)
			)
		)
		(zone
			(layer "F.Cu")
			(hatch none 0.5)
			(connect_pads
				(clearance 0)
			)
			(min_thickness 0.25)
			(keepout
				(tracks not_allowed)
				(vias allowed)
				(pads allowed)
				(copperpour not_allowed)
				(footprints allowed)
			)
			(placement
				(enabled no)
				(sheetname "")
			)
			(fill
				(thermal_gap 0.5)
				(thermal_bridge_width 0.5)
				(island_removal_mode 0)
			)
			(polygon
				(pts
					(xy 173.101 -130.8735) (xy 173.609 -130.8735) (xy 173.609 -131.2545) (xy 173.101 -131.2545)
				)
			)
		)
	)
	(footprint ""
		(layer "F.Cu")
		(at 434.7718 -14.859 180)
		(property "Reference" "R6W43"
			(at -0.8382 -0.67818 180)
			(unlocked yes)
			(layer "F.SilkS")
			(effects
				(font
					(size 0.4064 0.254)
					(thickness 0.1524)
				)
				(justify left)
			)
		)
		(property "Value" ""
			(at 0 0 180)
			(layer "F.Fab")
			(effects
				(font
					(size 1.27 1.27)
				)
			)
		)
		(duplicate_pad_numbers_are_jumpers no)
		(fp_poly
			(pts
				(xy -0.2794 -0.1016) (xy 0.2794 -0.1016) (xy 0.2794 0.9906) (xy -0.2794 0.9906)
			)
			(stroke
				(width 0)
				(type default)
			)
			(fill no)
			(layer "F.CrtYd")
		)
		(fp_line
			(start 0.2794 0.9906)
			(end 0.2794 -0.1016)
			(stroke
				(width 0.1)
				(type default)
			)
			(layer "F.Fab")
		)
		(fp_line
			(start 0.2794 -0.1016)
			(end -0.2794 -0.1016)
			(stroke
				(width 0.1)
				(type default)
			)
			(layer "F.Fab")
		)
		(fp_line
			(start -0.2794 0.9906)
			(end 0.2794 0.9906)
			(stroke
				(width 0.1)
				(type default)
			)
			(layer "F.Fab")
		)
		(fp_line
			(start -0.2794 -0.1016)
			(end -0.2794 0.9906)
			(stroke
				(width 0.1)
				(type default)
			)
			(layer "F.Fab")
		)
		(pad "1" smd rect
			(at 0 0 180)
			(size 0.508 0.508)
			(layers "F.Cu" "F.Mask" "F.Paste")
			(net "P3V3_STBY")
		)
		(pad "2" smd rect
			(at 0 0.889 180)
			(size 0.508 0.508)
			(layers "F.Cu" "F.Mask" "F.Paste")
			(net "PCA9554_A1")
		)
		(zone
			(layer "F.Cu")
			(hatch none 0.5)
			(connect_pads
				(clearance 0)
			)
			(min_thickness 0.25)
			(keepout
				(tracks not_allowed)
				(vias allowed)
				(pads allowed)
				(copperpour not_allowed)
				(footprints allowed)
			)
			(placement
				(enabled no)
				(sheetname "")
			)
			(fill
				(thermal_gap 0.5)
				(thermal_bridge_width 0.5)
				(island_removal_mode 0)
			)
			(polygon
				(pts
					(xy 435.0258 -15.494) (xy 434.5178 -15.494) (xy 434.5178 -15.113) (xy 435.0258 -15.113)
				)
			)
		)
		(zone
			(layer "F.Cu")
			(hatch none 0.5)
			(connect_pads
				(clearance 0)
			)
			(min_thickness 0.25)
			(keepout
				(tracks allowed)
				(vias not_allowed)
				(pads allowed)
				(copperpour not_allowed)
				(footprints allowed)
			)
			(placement
				(enabled no)
				(sheetname "")
			)
			(fill
				(thermal_gap 0.5)
				(thermal_bridge_width 0.5)
				(island_removal_mode 0)
			)
			(polygon
				(pts
					(xy 435.0258 -15.113) (xy 434.5178 -15.113) (xy 434.5178 -15.494) (xy 435.0258 -15.494)
				)
			)
		)
	)
	(footprint ""
		(layer "F.Cu")
		(at 352.714814 -103.103934 -90)
		(property "Reference" "L7C1"
			(at 0 0 270)
			(layer "F.SilkS")
			(hide yes)
			(effects
				(font
					(size 1.27 1.27)
				)
			)
		)
		(property "Value" "*"
			(at -3.5941 0.3429 270)
			(unlocked yes)
			(layer "F.Fab")
			(hide yes)
			(effects
				(font
					(size 1.27 1.016)
					(thickness 0.1524)
				)
			)
		)
		(property "Device Type" "IND-100NH-35-GP_DISCRET-G8-INDA"
			(at -3.5941 -1.1811 270)
			(unlocked yes)
			(layer "F.Fab")
			(hide yes)
			(effects
				(font
					(size 1.27 1.016)
					(thickness 0.1524)
				)
			)
		)
		(duplicate_pad_numbers_are_jumpers no)
		(fp_line
			(start -2.2479 2.794)
			(end -2.2479 -2.794)
			(stroke
				(width 0.1524)
				(type default)
			)
			(layer "F.SilkS")
		)
		(fp_line
			(start 2.2479 2.794)
			(end -2.2479 2.794)
			(stroke
				(width 0.1524)
				(type default)
			)
			(layer "F.SilkS")
		)
		(fp_line
			(start -2.2479 -2.794)
			(end 2.2479 -2.794)
			(stroke
				(width 0.1524)
				(type default)
			)
			(layer "F.SilkS")
		)
		(fp_line
			(start 2.2479 -2.794)
			(end 2.2479 2.794)
			(stroke
				(width 0.1524)
				(type default)
			)
			(layer "F.SilkS")
		)
		(fp_poly
			(pts
				(xy -1.9939 1.9939) (xy 1.9939 1.9939) (xy 1.9939 -1.9939) (xy -1.9939 -1.9939)
			)
			(stroke
				(width 0)
				(type default)
			)
			(fill no)
			(layer "F.CrtYd")
		)
		(fp_poly
			(pts
				(xy -2.5019 2.8702) (xy -2.5019 1.9939) (xy 1.9939 1.9939) (xy 1.9939 -1.9939) (xy -1.9939 -1.9939)
				(xy -1.9939 1.9812) (xy -2.5019 1.9812) (xy -2.5019 -2.8702) (xy 2.5019 -2.8702) (xy 2.5019 2.8702)
			)
			(stroke
				(width 0)
				(type default)
			)
			(fill no)
			(layer "F.CrtYd")
		)
		(fp_rect
			(start -2.5019 2.8702)
			(end 2.5019 -2.8702)
			(stroke
				(width 0)
				(type default)
			)
			(fill no)
			(layer "F.Fab")
		)
		(pad "1" smd rect
			(at 0 -1.745996 270)
			(size 1.5494 1.6002)
			(layers "F.Cu" "F.Mask" "F.Paste")
			(net "P12V_STBY")
		)
		(pad "2" smd rect
			(at 0 1.745996 270)
			(size 1.5494 1.6002)
			(layers "F.Cu" "F.Mask" "F.Paste")
			(net "VR_FET_SW_P12V_STBY_PVCCIO_CPU0")
		)
	)
	(footprint ""
		(layer "F.Cu")
		(at 263.186672 -77.636116)
		(property "Reference" "C5D28"
			(at 0 0 0)
			(layer "F.SilkS")
			(hide yes)
			(effects
				(font
					(size 1.27 1.27)
				)
			)
		)
		(property "Value" ""
			(at 0 0 0)
			(layer "F.Fab")
			(effects
				(font
					(size 1.27 1.27)
				)
			)
		)
		(duplicate_pad_numbers_are_jumpers no)
		(fp_poly
			(pts
				(xy -0.4953 -0.2032) (xy 0.4953 -0.2032) (xy 0.4953 1.6002) (xy -0.4953 1.6002)
			)
			(stroke
				(width 0)
				(type default)
			)
			(fill no)
			(layer "F.CrtYd")
		)
		(fp_line
			(start -0.4953 -0.2032)
			(end 0.4953 -0.2032)
			(stroke
				(width 0.1)
				(type default)
			)
			(layer "F.Fab")
		)
		(fp_line
			(start -0.4953 1.6002)
			(end -0.4953 -0.2032)
			(stroke
				(width 0.1)
				(type default)
			)
			(layer "F.Fab")
		)
		(fp_line
			(start 0.4953 -0.2032)
			(end 0.4953 1.6002)
			(stroke
				(width 0.1)
				(type default)
			)
			(layer "F.Fab")
		)
		(fp_line
			(start 0.4953 1.6002)
			(end -0.4953 1.6002)
			(stroke
				(width 0.1)
				(type default)
			)
			(layer "F.Fab")
		)
		(pad "1" smd rect
			(at 0 0)
			(size 0.762 0.889)
			(layers "F.Cu" "F.Mask" "F.Paste")
			(net "PVCCIN_CPU0")
		)
		(pad "2" smd rect
			(at 0 1.397)
			(size 0.762 0.889)
			(layers "F.Cu" "F.Mask" "F.Paste")
			(net "GND")
		)
		(zone
			(layer "F.Cu")
			(hatch none 0.5)
			(connect_pads
				(clearance 0)
			)
			(min_thickness 0.25)
			(keepout
				(tracks not_allowed)
				(vias allowed)
				(pads allowed)
				(copperpour not_allowed)
				(footprints allowed)
			)
			(placement
				(enabled no)
				(sheetname "")
			)
			(fill
				(thermal_gap 0.5)
				(thermal_bridge_width 0.5)
				(island_removal_mode 0)
			)
			(polygon
				(pts
					(xy 262.805672 -77.191616) (xy 263.567672 -77.191616) (xy 263.567672 -76.683616) (xy 262.805672 -76.683616)
				)
			)
		)
	)
	(footprint ""
		(layer "F.Cu")
		(at 24.384 -73.9648)
		(property "Reference" "C1D19"
			(at 0 0 0)
			(layer "F.SilkS")
			(hide yes)
			(effects
				(font
					(size 1.27 1.27)
				)
			)
		)
		(property "Value" ""
			(at 0 0 0)
			(layer "F.Fab")
			(effects
				(font
					(size 1.27 1.27)
				)
			)
		)
		(duplicate_pad_numbers_are_jumpers no)
		(fp_poly
			(pts
				(xy 0.3048 -0.1016) (xy 0.3048 0.9906) (xy -0.3048 0.9906) (xy -0.3048 -0.1016)
			)
			(stroke
				(width 0)
				(type default)
			)
			(fill no)
			(layer "F.CrtYd")
		)
		(fp_line
			(start -0.3048 -0.1016)
			(end -0.3048 0.9906)
			(stroke
				(width 0.1)
				(type default)
			)
			(layer "F.Fab")
		)
		(fp_line
			(start -0.3048 0.9906)
			(end 0.3048 0.9906)
			(stroke
				(width 0.1)
				(type default)
			)
			(layer "F.Fab")
		)
		(fp_line
			(start 0.3048 -0.1016)
			(end -0.3048 -0.1016)
			(stroke
				(width 0.1)
				(type default)
			)
			(layer "F.Fab")
		)
		(fp_line
			(start 0.3048 0.9906)
			(end 0.3048 -0.1016)
			(stroke
				(width 0.1)
				(type default)
			)
			(layer "F.Fab")
		)
		(pad "1" smd rect
			(at 0 0)
			(size 0.508 0.508)
			(layers "F.Cu" "F.Mask" "F.Paste")
			(net "A_HSC_VCAP")
		)
		(pad "2" smd rect
			(at 0 0.889)
			(size 0.508 0.508)
			(layers "F.Cu" "F.Mask" "F.Paste")
			(net "AGND_HSC")
		)
		(zone
			(layer "F.Cu")
			(hatch none 0.5)
			(connect_pads
				(clearance 0)
			)
			(min_thickness 0.25)
			(keepout
				(tracks allowed)
				(vias not_allowed)
				(pads allowed)
				(copperpour not_allowed)
				(footprints allowed)
			)
			(placement
				(enabled no)
				(sheetname "")
			)
			(fill
				(thermal_gap 0.5)
				(thermal_bridge_width 0.5)
				(island_removal_mode 0)
			)
			(polygon
				(pts
					(xy 24.13 -73.7108) (xy 24.638 -73.7108) (xy 24.638 -73.3298) (xy 24.13 -73.3298)
				)
			)
		)
		(zone
			(layer "F.Cu")
			(hatch none 0.5)
			(connect_pads
				(clearance 0)
			)
			(min_thickness 0.25)
			(keepout
				(tracks not_allowed)
				(vias allowed)
				(pads allowed)
				(copperpour not_allowed)
				(footprints allowed)
			)
			(placement
				(enabled no)
				(sheetname "")
			)
			(fill
				(thermal_gap 0.5)
				(thermal_bridge_width 0.5)
				(island_removal_mode 0)
			)
			(polygon
				(pts
					(xy 24.13 -73.3298) (xy 24.638 -73.3298) (xy 24.638 -73.7108) (xy 24.13 -73.7108)
				)
			)
		)
	)
)
